# T6G (Grand Teton) — schematic netlist excerpt (pin names and nets, part order shuffled) for the footprints in the layout excerpt that follows; sources: Cadence DE-HDL packaged netlist, KiCad conversion of 04192023_DAF0TMB3IC0_F0TG_MB_C_brd_V02_OCP.brd

C6503  Q_CAP_DIFFBUS  DIFF BUS_0.22UF 6.3V 20% X6S  pkg C0201  page 275 : \1\ = P5E_CPU0_P0_TX_BUF_C_DP<1> ; \2\ = P5E_CPU0_P0_TX_BUF_DP<1>
R1195  Q_RES  4.7K 5% EMPTY  pkg 0402LF  page 83 : A = P12V_OCP_SFF_EN_R ; B = P3V3_AUX
PR353  Q_RES  8.87K 1% EMPTY  pkg 0402LF  page 196 : A = GND ; B = PVDDCR_CPU0_P0_LSET5

(kicad_pcb
	(version 20260206)
	(generator "pcbnew")
	(generator_version "10.0")
	(general
		(thickness 1.6)
		(legacy_teardrops no)
	)
	(paper "A4")
	(title_block
		(title "04192023_DAF0TMB3IC0_F0TG_MB_C_brd_V02_OCP.brd")
		(comment 1 "Grand Teton / footprints 1831-1833 of 8354")
	)
	(layers
		(0 "F.Cu" signal "TOP")
		(4 "In1.Cu" signal "GND")
		(6 "In2.Cu" signal "IN1")
		(8 "In3.Cu" signal "GND1")
		(10 "In4.Cu" signal "IN2")
		(12 "In5.Cu" signal "GND2")
		(14 "In6.Cu" signal "IN3")
		(16 "In7.Cu" signal "GND3")
		(18 "In8.Cu" signal "VCC")
		(20 "In9.Cu" signal "VCC1")
		(22 "In10.Cu" signal "GND4")
		(24 "In11.Cu" signal "IN4")
		(26 "In12.Cu" signal "GND5")
		(28 "In13.Cu" signal "IN5")
		(30 "In14.Cu" signal "GND6")
		(32 "In15.Cu" signal "IN6")
		(34 "In16.Cu" signal "GND7")
		(2 "B.Cu" signal "BOTTOM")
		(9 "F.Adhes" user "F.Adhesive")
		(11 "B.Adhes" user "B.Adhesive")
		(13 "F.Paste" user "Package Geometry/Pastemask Top")
		(15 "B.Paste" user "Package Geometry/Pastemask Bottom")
		(5 "F.SilkS" user "Ref Des/Silkscreen Top")
		(7 "B.SilkS" user "Ref Des/Silkscreen Bottom")
		(1 "F.Mask" user "Board Geometry/Soldermask Top")
		(3 "B.Mask" user "Board Geometry/Soldermask Bottom")
		(17 "Dwgs.User" user "User.Drawings")
		(19 "Cmts.User" user "User.Comments")
		(21 "Eco1.User" user "User.Eco1")
		(23 "Eco2.User" user "User.Eco2")
		(25 "Edge.Cuts" user "Board Geometry/Outline")
		(27 "Margin" user)
		(31 "F.CrtYd" user "Package Geometry/Place Bound Top")
		(29 "B.CrtYd" user "Package Geometry/Place Bound Bottom")
		(35 "F.Fab" user "Ref Des/Assembly Top")
		(33 "B.Fab" user "Ref Des/Assembly Bottom")
	)
	(footprint ""
		(layer "F.Cu")
		(at 357.338122 -164.284406)
		(property "Reference" "PR353"
			(at 0 0 0)
			(layer "F.SilkS")
			(hide yes)
			(effects
				(font
					(size 1.27 1.27)
				)
			)
		)
		(property "Value" ""
			(at 0 0 0)
			(layer "F.Fab")
			(effects
				(font
					(size 1.27 1.27)
				)
			)
		)
		(duplicate_pad_numbers_are_jumpers no)
		(fp_line
			(start -0.7874 -0.4064)
			(end 0.7874 -0.4064)
			(stroke
				(width 0.1524)
				(type default)
			)
			(layer "F.SilkS")
		)
		(fp_line
			(start -0.7874 0.4064)
			(end -0.7874 -0.4064)
			(stroke
				(width 0.1524)
				(type default)
			)
			(layer "F.SilkS")
		)
		(fp_line
			(start 0.7874 -0.4064)
			(end 0.7874 0.4064)
			(stroke
				(width 0.1524)
				(type default)
			)
			(layer "F.SilkS")
		)
		(fp_line
			(start 0.7874 0.4064)
			(end -0.7874 0.4064)
			(stroke
				(width 0.1524)
				(type default)
			)
			(layer "F.SilkS")
		)
		(fp_line
			(start -0.67945 -0.305054)
			(end -0.12065 -0.305054)
			(stroke
				(width 0.1)
				(type default)
			)
			(layer "F.Fab")
		)
		(fp_line
			(start -0.67945 0.3048)
			(end -0.67945 -0.305054)
			(stroke
				(width 0.1)
				(type default)
			)
			(layer "F.Fab")
		)
		(fp_line
			(start -0.12065 -0.305054)
			(end -0.12065 -0.2794)
			(stroke
				(width 0.1)
				(type default)
			)
			(layer "F.Fab")
		)
		(fp_line
			(start -0.12065 -0.2794)
			(end 0.12065 -0.2794)
			(stroke
				(width 0.1)
				(type default)
			)
			(layer "F.Fab")
		)
		(fp_line
			(start -0.12065 0.2794)
			(end -0.12065 0.3048)
			(stroke
				(width 0.1)
				(type default)
			)
			(layer "F.Fab")
		)
		(fp_line
			(start -0.12065 0.3048)
			(end -0.67945 0.3048)
			(stroke
				(width 0.1)
				(type default)
			)
			(layer "F.Fab")
		)
		(fp_line
			(start 0.120396 0.2794)
			(end -0.12065 0.2794)
			(stroke
				(width 0.1)
				(type default)
			)
			(layer "F.Fab")
		)
		(fp_line
			(start 0.120396 0.3048)
			(end 0.120396 0.2794)
			(stroke
				(width 0.1)
				(type default)
			)
			(layer "F.Fab")
		)
		(fp_line
			(start 0.12065 -0.3048)
			(end 0.67945 -0.3048)
			(stroke
				(width 0.1)
				(type default)
			)
			(layer "F.Fab")
		)
		(fp_line
			(start 0.12065 -0.2794)
			(end 0.12065 -0.3048)
			(stroke
				(width 0.1)
				(type default)
			)
			(layer "F.Fab")
		)
		(fp_line
			(start 0.67945 -0.3048)
			(end 0.67945 0.3048)
			(stroke
				(width 0.1)
				(type default)
			)
			(layer "F.Fab")
		)
		(fp_line
			(start 0.67945 0.3048)
			(end 0.120396 0.3048)
			(stroke
				(width 0.1)
				(type default)
			)
			(layer "F.Fab")
		)
		(pad "1" smd circle
			(at -0.40005 0)
			(size 0 0)
			(layers "F.Cu" "F.Mask" "F.Paste")
			(net "GND")
		)
		(pad "2" smd circle
			(at 0.40005 0)
			(size 0 0)
			(layers "F.Cu" "F.Mask" "F.Paste")
			(net "PVDDCR_CPU0_P0_LSET5")
		)
	)
	(footprint ""
		(layer "F.Cu")
		(at 163.703 -110.200948 180)
		(property "Reference" "R1195"
			(at 0 0 180)
			(layer "F.SilkS")
			(hide yes)
			(effects
				(font
					(size 1.27 1.27)
				)
			)
		)
		(property "Value" ""
			(at 0 0 180)
			(layer "F.Fab")
			(effects
				(font
					(size 1.27 1.27)
				)
			)
		)
		(duplicate_pad_numbers_are_jumpers no)
		(fp_line
			(start 0.7874 0.4064)
			(end -0.7874 0.4064)
			(stroke
				(width 0.1524)
				(type default)
			)
			(layer "F.SilkS")
		)
		(fp_line
			(start 0.7874 -0.4064)
			(end 0.7874 0.4064)
			(stroke
				(width 0.1524)
				(type default)
			)
			(layer "F.SilkS")
		)
		(fp_line
			(start -0.7874 0.4064)
			(end -0.7874 -0.4064)
			(stroke
				(width 0.1524)
				(type default)
			)
			(layer "F.SilkS")
		)
		(fp_line
			(start -0.7874 -0.4064)
			(end 0.7874 -0.4064)
			(stroke
				(width 0.1524)
				(type default)
			)
			(layer "F.SilkS")
		)
		(fp_line
			(start 0.67945 0.3048)
			(end 0.120396 0.3048)
			(stroke
				(width 0.1)
				(type default)
			)
			(layer "F.Fab")
		)
		(fp_line
			(start 0.67945 -0.3048)
			(end 0.67945 0.3048)
			(stroke
				(width 0.1)
				(type default)
			)
			(layer "F.Fab")
		)
		(fp_line
			(start 0.12065 -0.2794)
			(end 0.12065 -0.3048)
			(stroke
				(width 0.1)
				(type default)
			)
			(layer "F.Fab")
		)
		(fp_line
			(start 0.12065 -0.3048)
			(end 0.67945 -0.3048)
			(stroke
				(width 0.1)
				(type default)
			)
			(layer "F.Fab")
		)
		(fp_line
			(start 0.120396 0.3048)
			(end 0.120396 0.2794)
			(stroke
				(width 0.1)
				(type default)
			)
			(layer "F.Fab")
		)
		(fp_line
			(start 0.120396 0.2794)
			(end -0.12065 0.2794)
			(stroke
				(width 0.1)
				(type default)
			)
			(layer "F.Fab")
		)
		(fp_line
			(start -0.12065 0.3048)
			(end -0.67945 0.3048)
			(stroke
				(width 0.1)
				(type default)
			)
			(layer "F.Fab")
		)
		(fp_line
			(start -0.12065 0.2794)
			(end -0.12065 0.3048)
			(stroke
				(width 0.1)
				(type default)
			)
			(layer "F.Fab")
		)
		(fp_line
			(start -0.12065 -0.2794)
			(end 0.12065 -0.2794)
			(stroke
				(width 0.1)
				(type default)
			)
			(layer "F.Fab")
		)
		(fp_line
			(start -0.12065 -0.305054)
			(end -0.12065 -0.2794)
			(stroke
				(width 0.1)
				(type default)
			)
			(layer "F.Fab")
		)
		(fp_line
			(start -0.67945 0.3048)
			(end -0.67945 -0.305054)
			(stroke
				(width 0.1)
				(type default)
			)
			(layer "F.Fab")
		)
		(fp_line
			(start -0.67945 -0.305054)
			(end -0.12065 -0.305054)
			(stroke
				(width 0.1)
				(type default)
			)
			(layer "F.Fab")
		)
		(pad "1" smd circle
			(at -0.40005 0 180)
			(size 0 0)
			(layers "F.Cu" "F.Mask" "F.Paste")
			(net "P12V_OCP_SFF_EN_R")
		)
		(pad "2" smd circle
			(at 0.40005 0 180)
			(size 0 0)
			(layers "F.Cu" "F.Mask" "F.Paste")
			(net "P3V3_AUX")
		)
	)
	(footprint ""
		(layer "F.Cu")
		(at 307.746146 -416.899344 -90)
		(property "Reference" "C6503"
			(at 0 0 270)
			(layer "F.SilkS")
			(hide yes)
			(effects
				(font
					(size 1.27 1.27)
				)
			)
		)
		(property "Value" ""
			(at 0 0 270)
			(layer "F.Fab")
			(effects
				(font
					(size 1.27 1.27)
				)
			)
		)
		(duplicate_pad_numbers_are_jumpers no)
		(fp_line
			(start -0.299974 0.150114)
			(end -0.299974 -0.150114)
			(stroke
				(width 0.1)
				(type default)
			)
			(layer "F.Fab")
		)
		(fp_line
			(start 0.299974 0.150114)
			(end -0.299974 0.150114)
			(stroke
				(width 0.1)
				(type default)
			)
			(layer "F.Fab")
		)
		(fp_line
			(start -0.299974 -0.150114)
			(end 0.299974 -0.150114)
			(stroke
				(width 0.1)
				(type default)
			)
			(layer "F.Fab")
		)
		(fp_line
			(start 0.299974 -0.150114)
			(end 0.299974 0.150114)
			(stroke
				(width 0.1)
				(type default)
			)
			(layer "F.Fab")
		)
		(pad "1" smd rect
			(at -0.2667 0 270)
			(size 0.3048 0.381)
			(layers "F.Cu" "F.Mask" "F.Paste")
			(net "P5E_CPU0_P0_TX_BUF_C_DP<1>")
		)
		(pad "2" smd rect
			(at 0.2667 0 270)
			(size 0.3048 0.381)
			(layers "F.Cu" "F.Mask" "F.Paste")
			(net "P5E_CPU0_P0_TX_BUF_DP<1>")
		)
	)
)
